(kicad_pcb
	(version 20221018)
	(generator pcbnew)
	(general
    (thickness 1.562)
  )
	(paper "A4")
	(title_block
    (title "Thunderbolt PCIe Adaper")
    (date "2024-07-09")
    (rev "1.0.3")
    (comment 1 "www.antmicro.com")
    (comment 2 "Antmicro Ltd.")
		(comment 9 "footprints 194-201 of 271")
	)
	(layers
    (0 "F.Cu" signal)
    (1 "In1.Cu" signal)
    (2 "In2.Cu" signal)
    (3 "In3.Cu" signal)
    (4 "In4.Cu" signal)
    (31 "B.Cu" signal)
    (32 "B.Adhes" user "B.Adhesive")
    (33 "F.Adhes" user "F.Adhesive")
    (34 "B.Paste" user)
    (35 "F.Paste" user)
    (36 "B.SilkS" user "B.Silkscreen")
    (37 "F.SilkS" user "F.Silkscreen")
    (38 "B.Mask" user)
    (39 "F.Mask" user)
    (40 "Dwgs.User" user "User.Drawings")
    (41 "Cmts.User" user "User.Comments")
    (42 "Eco1.User" user "User.Eco1")
    (43 "Eco2.User" user "User.Eco2")
    (44 "Edge.Cuts" user)
    (45 "Margin" user)
    (46 "B.CrtYd" user "B.Courtyard")
    (47 "F.CrtYd" user "F.Courtyard")
    (48 "B.Fab" user)
    (49 "F.Fab" user)
  )
	(footprint "antmicro-footprints:C_0402_1005Metric" (layer "B.Cu")
    (at 140.16 78.37 -90)
    (descr "Capacitor SMD 0402")
    (tags "capacitor SMD 0402")
    (property "Author" "Antmicro")
    (property "Dielectric" "")
    (property "License" "Apache-2.0")
    (property "MPN" "CC0402MRX5R5BB106")
    (property "Manufacturer" "YAGEO")
    (property "Sheetfile" "tb-power.kicad_sch")
    (property "Sheetname" "Thunderbolt Controller - Power")
    (property "Val" "10u")
    (property "Voltage" "")
    (property "ki_description" "SMD Multilayer Ceramic Capacitor, 10 µF, 6.3 V, 0402 [1005 Metric], ± 20%, X5R, CC Series")
    (property "ki_keywords" "0402, SMT, CAPACITOR, PASSIVE, MLCC, CERAMIC")
    (attr smd)
    (fp_text reference "C75" (at 6.466 -17.066 90) (layer "B.SilkS")
        (effects (font (size 0.7 0.7) (thickness 0.15)) (justify left bottom mirror))
    )
    (fp_text value "C_10u_0402" (at -1.022927 -2.155213 90) (layer "B.Fab")
        (effects (font (size 0.7 0.7) (thickness 0.15)) (justify left bottom mirror))
    )
    (fp_text user "Author: Antmicro" (at -0.939 -3.399 90) (layer "B.Fab") hide
        (effects (font (size 0.7 0.7) (thickness 0.15)) (justify left bottom mirror))
    )
    (fp_text user "License: Apache-2.0" (at -0.939 -5.799 90) (layer "B.Fab") hide
        (effects (font (size 0.7 0.7) (thickness 0.15)) (justify left bottom mirror))
    )
    (fp_text user "${REFERENCE}" (at -0.939 -4.599 90) (layer "B.Fab") hide
        (effects (font (size 0.7 0.7) (thickness 0.15)) (justify left bottom mirror))
    )
    (fp_rect (start -0.925 0.47) (end 0.925 -0.47)
      (stroke (width 0.05) (type default)) (fill none) (layer "B.CrtYd"))
    (fp_line (start -0.494 -0.248) (end -0.494 0.25)
      (stroke (width 0.15) (type solid)) (layer "B.Fab"))
    (fp_line (start -0.494 0.25) (end 0.504 0.25)
      (stroke (width 0.15) (type solid)) (layer "B.Fab"))
    (fp_line (start 0.504 -0.248) (end -0.494 -0.248)
      (stroke (width 0.15) (type solid)) (layer "B.Fab"))
    (fp_line (start 0.504 0.25) (end 0.504 -0.248)
      (stroke (width 0.15) (type solid)) (layer "B.Fab"))
    (pad "1" smd roundrect (at -0.48 0 270) (size 0.59 0.64) (layers "B.Cu" "B.Paste" "B.Mask") (roundrect_rratio 0.25)
      (net 1 "GND") (pintype "passive"))
    (pad "2" smd roundrect (at 0.48 0 270) (size 0.59 0.64) (layers "B.Cu" "B.Paste" "B.Mask") (roundrect_rratio 0.25)
      (net 113 "Net-(U4A-VCC0P9_LVR_SENSE)") (pintype "passive"))
  )
	(footprint "antmicro-footprints:C_0402_1005Metric" (layer "B.Cu")
    (at 116.910001 63.205001)
    (descr "Capacitor SMD 0402")
    (tags "capacitor SMD 0402")
    (property "Author" "Antmicro")
    (property "Dielectric" "")
    (property "License" "Apache-2.0")
    (property "MPN" "C1005X6S1A105K050BC")
    (property "Manufacturer" "TDK")
    (property "Sheetfile" "power.kicad_sch")
    (property "Sheetname" "Power")
    (property "Val" "1u")
    (property "Voltage" "")
    (property "ki_description" "SMD Multilayer Ceramic Capacitor, 1 µF, 10 V, 0402 [1005 Metric], ± 10%, X6S, C")
    (property "ki_keywords" "0402, SMT, CAPACITOR, PASSIVE, CERAMIC, MLCC")
    (attr smd)
    (fp_text reference "C25" (at 3.104999 0.294999 180) (layer "B.SilkS")
        (effects (font (size 0.7 0.7) (thickness 0.15)) (justify left bottom mirror))
    )
    (fp_text value "C_1u_0402" (at -1.022927 -2.155213 180) (layer "B.Fab")
        (effects (font (size 0.7 0.7) (thickness 0.15)) (justify left bottom mirror))
    )
    (fp_text user "License: Apache-2.0" (at -0.939 -5.799 180) (layer "B.Fab") hide
        (effects (font (size 0.7 0.7) (thickness 0.15)) (justify left bottom mirror))
    )
    (fp_text user "Author: Antmicro" (at -0.939 -3.399 180) (layer "B.Fab") hide
        (effects (font (size 0.7 0.7) (thickness 0.15)) (justify left bottom mirror))
    )
    (fp_text user "${REFERENCE}" (at -0.939 -4.599 180) (layer "B.Fab") hide
        (effects (font (size 0.7 0.7) (thickness 0.15)) (justify left bottom mirror))
    )
    (fp_rect (start -0.925 0.47) (end 0.925 -0.47)
      (stroke (width 0.05) (type default)) (fill none) (layer "B.CrtYd"))
    (fp_line (start -0.494 -0.248) (end -0.494 0.25)
      (stroke (width 0.15) (type solid)) (layer "B.Fab"))
    (fp_line (start -0.494 0.25) (end 0.504 0.25)
      (stroke (width 0.15) (type solid)) (layer "B.Fab"))
    (fp_line (start 0.504 -0.248) (end -0.494 -0.248)
      (stroke (width 0.15) (type solid)) (layer "B.Fab"))
    (fp_line (start 0.504 0.25) (end 0.504 -0.248)
      (stroke (width 0.15) (type solid)) (layer "B.Fab"))
    (pad "1" smd roundrect (at -0.48 0) (size 0.59 0.64) (layers "B.Cu" "B.Paste" "B.Mask") (roundrect_rratio 0.25)
      (net 1 "GND") (pintype "passive"))
    (pad "2" smd roundrect (at 0.48 0) (size 0.59 0.64) (layers "B.Cu" "B.Paste" "B.Mask") (roundrect_rratio 0.25)
      (net 6 "/Power/SMPS_LDO") (pintype "passive"))
  )
	(footprint "antmicro-footprints:C_0402_1005Metric" (layer "B.Cu")
    (at 132.85 76.925)
    (descr "Capacitor SMD 0402")
    (tags "capacitor SMD 0402")
    (property "Author" "Antmicro")
    (property "Dielectric" "")
    (property "License" "Apache-2.0")
    (property "MPN" "C1005X6S1A105K050BC")
    (property "Manufacturer" "TDK")
    (property "Sheetfile" "tb-power.kicad_sch")
    (property "Sheetname" "Thunderbolt Controller - Power")
    (property "Val" "1u")
    (property "Voltage" "")
    (property "ki_description" "SMD Multilayer Ceramic Capacitor, 1 µF, 10 V, 0402 [1005 Metric], ± 10%, X6S, C")
    (property "ki_keywords" "0402, SMT, CAPACITOR, PASSIVE, CERAMIC, MLCC")
    (attr smd)
    (fp_text reference "C71" (at 17.518 7.53 180) (layer "B.SilkS")
        (effects (font (size 0.7 0.7) (thickness 0.15)) (justify left bottom mirror))
    )
    (fp_text value "C_1u_0402" (at -1.022927 -2.155213 180) (layer "B.Fab")
        (effects (font (size 0.7 0.7) (thickness 0.15)) (justify left bottom mirror))
    )
    (fp_text user "Author: Antmicro" (at -0.939 -3.399 180) (layer "B.Fab") hide
        (effects (font (size 0.7 0.7) (thickness 0.15)) (justify left bottom mirror))
    )
    (fp_text user "License: Apache-2.0" (at -0.939 -5.799 180) (layer "B.Fab") hide
        (effects (font (size 0.7 0.7) (thickness 0.15)) (justify left bottom mirror))
    )
    (fp_text user "${REFERENCE}" (at -0.939 -4.599 180) (layer "B.Fab") hide
        (effects (font (size 0.7 0.7) (thickness 0.15)) (justify left bottom mirror))
    )
    (fp_rect (start -0.925 0.47) (end 0.925 -0.47)
      (stroke (width 0.05) (type default)) (fill none) (layer "B.CrtYd"))
    (fp_line (start -0.494 -0.248) (end -0.494 0.25)
      (stroke (width 0.15) (type solid)) (layer "B.Fab"))
    (fp_line (start -0.494 0.25) (end 0.504 0.25)
      (stroke (width 0.15) (type solid)) (layer "B.Fab"))
    (fp_line (start 0.504 -0.248) (end -0.494 -0.248)
      (stroke (width 0.15) (type solid)) (layer "B.Fab"))
    (fp_line (start 0.504 0.25) (end 0.504 -0.248)
      (stroke (width 0.15) (type solid)) (layer "B.Fab"))
    (pad "1" smd roundrect (at -0.48 0) (size 0.59 0.64) (layers "B.Cu" "B.Paste" "B.Mask") (roundrect_rratio 0.25)
      (net 1 "GND") (pintype "passive"))
    (pad "2" smd roundrect (at 0.48 0) (size 0.59 0.64) (layers "B.Cu" "B.Paste" "B.Mask") (roundrect_rratio 0.25)
      (net 111 "Net-(U4A-VCC3P3_LC)") (pintype "passive"))
  )
	(footprint "antmicro-footprints:R_0402_1005Metric" (layer "B.Cu")
    (at 154.89 57.39 90)
    (descr "Resistor SMD 0402")
    (tags "resistor SMD 0402")
    (property "Author" "Antmicro")
    (property "License" "Apache-2.0")
    (property "MPN" "CR0402-FX-1003GLF")
    (property "Manufacturer" "Bourns")
    (property "Sheetfile" "power.kicad_sch")
    (property "Sheetname" "Power")
    (property "Tolerance" "1%")
    (property "Val" "100k")
    (property "ki_description" "SMD Chip Resistor, 100 kohm, ± 1%, 62.5 mW, 0402 [1005 Metric], Thick Film, General Purpose")
    (property "ki_keywords" "0402, SMT, RESISTOR, PASSIVE")
    (attr smd)
    (fp_text reference "R30" (at 3.034 0.431 270) (layer "B.SilkS")
        (effects (font (size 0.7 0.7) (thickness 0.15)) (justify left bottom mirror))
    )
    (fp_text value "R_100k_0402" (at -1.011843 -1.772047 270) (layer "B.Fab")
        (effects (font (size 0.7 0.7) (thickness 0.15)) (justify left bottom mirror))
    )
    (fp_text user "Author: Antmicro" (at -0.95 -4.169 270) (layer "B.Fab") hide
        (effects (font (size 0.7 0.7) (thickness 0.15)) (justify left bottom mirror))
    )
    (fp_text user "License: Apache-2.0" (at -0.95 -5.169 270) (layer "B.Fab") hide
        (effects (font (size 0.7 0.7) (thickness 0.15)) (justify left bottom mirror))
    )
    (fp_text user "${REFERENCE}" (at -0.95 -3.168 270) (layer "B.Fab") hide
        (effects (font (size 0.7 0.7) (thickness 0.15)) (justify left bottom mirror))
    )
    (fp_rect (start -0.925 0.47) (end 0.925 -0.47)
      (stroke (width 0.05) (type default)) (fill none) (layer "B.CrtYd"))
    (fp_rect (start -0.5 0.25) (end 0.5 -0.25)
      (stroke (width 0.15) (type solid)) (fill none) (layer "B.Fab"))
    (pad "1" smd roundrect (at -0.48 0 90) (size 0.59 0.64) (layers "B.Cu" "B.Paste" "B.Mask") (roundrect_rratio 0.25)
      (net 163 "Net-(U3-DEBUG_CTL1(GPIO16,_I2CADDR_B4))") (pintype "passive"))
    (pad "2" smd roundrect (at 0.48 0 90) (size 0.59 0.64) (layers "B.Cu" "B.Paste" "B.Mask") (roundrect_rratio 0.25)
      (net 9 "/Power/TPS_3V3") (pintype "passive"))
  )
	(footprint "antmicro-footprints:C_0603_1608Metric" (layer "B.Cu")
    (at 161.98 89.8 90)
    (descr "Capacitor SMD 0603")
    (tags "capacitor 0603")
    (property "Author" "Antmicro")
    (property "Dielectric" "")
    (property "License" "Apache-2.0")
    (property "MPN" "CL10A226MO7JZNC")
    (property "Manufacturer" "Samsung Electro-Mechanics")
    (property "Sheetfile" "power.kicad_sch")
    (property "Sheetname" "Power")
    (property "Val" "22u")
    (property "Voltage" "16V")
    (property "ki_description" "SMD Multilayer Ceramic Capacitor")
    (property "ki_keywords" "0603, SMT, CAPACITOR, PASSIVE, CERAMIC")
    (attr smd)
    (fp_text reference "C119" (at 4.202 0.4 270) (layer "B.SilkS")
        (effects (font (size 0.7 0.7) (thickness 0.15)) (justify left bottom mirror))
    )
    (fp_text value "C_22u_16V_0603" (at -1.42757 -1.770288 270) (layer "B.Fab")
        (effects (font (size 0.7 0.7) (thickness 0.15)) (justify left bottom mirror))
    )
    (fp_text user "${REFERENCE}" (at -1.682 -3.895 270) (layer "B.Fab") hide
        (effects (font (size 0.7 0.7) (thickness 0.15)) (justify left bottom mirror))
    )
    (fp_text user "License: Apache-2.0" (at -1.682 -5.895 270) (layer "B.Fab") hide
        (effects (font (size 0.7 0.7) (thickness 0.15)) (justify left bottom mirror))
    )
    (fp_text user "Author: Antmicro" (at -1.682 -4.894 270) (layer "B.Fab") hide
        (effects (font (size 0.7 0.7) (thickness 0.15)) (justify left bottom mirror))
    )
    (fp_line (start -0.15 -0.4) (end 0.15 -0.4)
      (stroke (width 0.15) (type solid)) (layer "B.SilkS"))
    (fp_line (start -0.15 0.4) (end 0.15 0.4)
      (stroke (width 0.15) (type solid)) (layer "B.SilkS"))
    (fp_rect (start -1.25 0.65) (end 1.25 -0.65)
      (stroke (width 0.05) (type solid)) (fill none) (layer "B.CrtYd"))
    (fp_rect (start -0.8 0.4) (end 0.8 -0.4)
      (stroke (width 0.15) (type solid)) (fill none) (layer "B.Fab"))
    (pad "1" smd roundrect (at -0.7 0 90) (size 0.8 1) (layers "B.Cu" "B.Paste" "B.Mask") (roundrect_rratio 0.2)
      (net 1 "GND") (pintype "passive"))
    (pad "2" smd roundrect (at 0.7 0 90) (size 0.8 1) (layers "B.Cu" "B.Paste" "B.Mask") (roundrect_rratio 0.2)
      (net 61 "12V0_MOLEX") (pintype "passive"))
  )
	(footprint "antmicro-footprints:C_0402_1005Metric" (layer "B.Cu")
    (at 165.2 74.444922 -90)
    (descr "Capacitor SMD 0402")
    (tags "capacitor SMD 0402")
    (property "Author" "Antmicro")
    (property "Dielectric" "X5R")
    (property "License" "Apache-2.0")
    (property "MPN" "GRM155R61H104KE14D")
    (property "Manufacturer" "Murata")
    (property "Sheetfile" "connectors.kicad_sch")
    (property "Sheetname" "Connectors")
    (property "Val" "100n")
    (property "Voltage" "50V")
    (property "ki_description" "SMD Multilayer Ceramic Capacitor, 0.1 µF, 50 V, 0402 [1005 Metric], ± 10%, X5R, GRM Series")
    (property "ki_keywords" "0402, SMT, CAPACITOR, PASSIVE, CERAMIC, MLCC")
    (attr smd)
    (fp_text reference "C4" (at -0.784922 0.608 90) (layer "B.SilkS")
        (effects (font (size 0.7 0.7) (thickness 0.15)) (justify left bottom mirror))
    )
    (fp_text value "C_100n_0402" (at -1.022927 -2.155213 90) (layer "B.Fab")
        (effects (font (size 0.7 0.7) (thickness 0.15)) (justify left bottom mirror))
    )
    (fp_text user "License: Apache-2.0" (at -0.939 -5.799 90) (layer "B.Fab") hide
        (effects (font (size 0.7 0.7) (thickness 0.15)) (justify left bottom mirror))
    )
    (fp_text user "Author: Antmicro" (at -0.939 -3.399 90) (layer "B.Fab") hide
        (effects (font (size 0.7 0.7) (thickness 0.15)) (justify left bottom mirror))
    )
    (fp_text user "${REFERENCE}" (at -0.939 -4.599 90) (layer "B.Fab") hide
        (effects (font (size 0.7 0.7) (thickness 0.15)) (justify left bottom mirror))
    )
    (fp_rect (start -0.925 0.47) (end 0.925 -0.47)
      (stroke (width 0.05) (type default)) (fill none) (layer "B.CrtYd"))
    (fp_line (start -0.494 -0.248) (end -0.494 0.25)
      (stroke (width 0.15) (type solid)) (layer "B.Fab"))
    (fp_line (start -0.494 0.25) (end 0.504 0.25)
      (stroke (width 0.15) (type solid)) (layer "B.Fab"))
    (fp_line (start 0.504 -0.248) (end -0.494 -0.248)
      (stroke (width 0.15) (type solid)) (layer "B.Fab"))
    (fp_line (start 0.504 0.25) (end 0.504 -0.248)
      (stroke (width 0.15) (type solid)) (layer "B.Fab"))
    (pad "1" smd roundrect (at -0.48 0 270) (size 0.59 0.64) (layers "B.Cu" "B.Paste" "B.Mask") (roundrect_rratio 0.25)
      (net 1 "GND") (pintype "passive"))
    (pad "2" smd roundrect (at 0.48 0 270) (size 0.59 0.64) (layers "B.Cu" "B.Paste" "B.Mask") (roundrect_rratio 0.25)
      (net 3 "5V0_USB") (pintype "passive"))
  )
	(footprint "antmicro-footprints:C_0402_1005Metric" (layer "B.Cu")
    (at 140.5 92.65 -90)
    (descr "Capacitor SMD 0402")
    (tags "capacitor SMD 0402")
    (property "Author" "Antmicro")
    (property "Dielectric" "")
    (property "License" "Apache-2.0")
    (property "MPN" "CC0402KRX5R6BB224")
    (property "Manufacturer" "YAGEO")
    (property "Sheetfile" "tb.kicad_sch")
    (property "Sheetname" "TB Controller")
    (property "Val" "220n")
    (property "Voltage" "")
    (property "ki_description" "SMD Multilayer Ceramic Capacitor, 0.22 µF, 10 V, 0402 [1005 Metric], ± 10%, X5R, CC Series")
    (property "ki_keywords" "0402, SMT, CAPACITOR, PASSIVE, MLCC, CERAMIC")
    (attr smd)
    (fp_text reference "C108" (at -3.877 -0.47 90) (layer "B.SilkS")
        (effects (font (size 0.7 0.7) (thickness 0.15)) (justify left bottom mirror))
    )
    (fp_text value "C_220n_0402" (at -1.022927 -2.155213 90) (layer "B.Fab")
        (effects (font (size 0.7 0.7) (thickness 0.15)) (justify left bottom mirror))
    )
    (fp_text user "License: Apache-2.0" (at -0.939 -5.799 90) (layer "B.Fab") hide
        (effects (font (size 0.7 0.7) (thickness 0.15)) (justify left bottom mirror))
    )
    (fp_text user "Author: Antmicro" (at -0.939 -3.399 90) (layer "B.Fab") hide
        (effects (font (size 0.7 0.7) (thickness 0.15)) (justify left bottom mirror))
    )
    (fp_text user "${REFERENCE}" (at -0.939 -4.599 90) (layer "B.Fab") hide
        (effects (font (size 0.7 0.7) (thickness 0.15)) (justify left bottom mirror))
    )
    (fp_rect (start -0.925 0.47) (end 0.925 -0.47)
      (stroke (width 0.05) (type default)) (fill none) (layer "B.CrtYd"))
    (fp_line (start -0.494 -0.248) (end -0.494 0.25)
      (stroke (width 0.15) (type solid)) (layer "B.Fab"))
    (fp_line (start -0.494 0.25) (end 0.504 0.25)
      (stroke (width 0.15) (type solid)) (layer "B.Fab"))
    (fp_line (start 0.504 -0.248) (end -0.494 -0.248)
      (stroke (width 0.15) (type solid)) (layer "B.Fab"))
    (fp_line (start 0.504 0.25) (end 0.504 -0.248)
      (stroke (width 0.15) (type solid)) (layer "B.Fab"))
    (pad "1" smd roundrect (at -0.48 0 270) (size 0.59 0.64) (layers "B.Cu" "B.Paste" "B.Mask") (roundrect_rratio 0.25)
      (net 79 "/TB Controller/TX3_N") (pintype "passive"))
    (pad "2" smd roundrect (at 0.48 0 270) (size 0.59 0.64) (layers "B.Cu" "B.Paste" "B.Mask") (roundrect_rratio 0.25)
      (net 27 "PCIE_TX3_N") (pintype "passive"))
  )
	(footprint "antmicro-footprints:R_0402_1005Metric" (layer "B.Cu")
    (at 135.115 60.395)
    (descr "Resistor SMD 0402")
    (tags "resistor SMD 0402")
    (property "Author" "Antmicro")
    (property "License" "Apache-2.0")
    (property "MPN" "CR0402-FX-3301GLF")
    (property "Manufacturer" "Bourns")
    (property "Sheetfile" "tb.kicad_sch")
    (property "Sheetname" "TB Controller")
    (property "Tolerance" "1%")
    (property "Val" "3k3")
    (property "ki_description" "SMD Chip Resistor, 3.3 kohm, ± 1%, 63 mW, 0402 [1005 Metric], Thick Film, General Purpose")
    (property "ki_keywords" "0402, SMT, RESISTOR, PASSIVE")
    (attr smd)
    (fp_text reference "R52" (at -1.003 0.438 180) (layer "B.SilkS")
        (effects (font (size 0.7 0.7) (thickness 0.15)) (justify left bottom mirror))
    )
    (fp_text value "R_3k3_0402" (at -1.011843 -1.772047 180) (layer "B.Fab")
        (effects (font (size 0.7 0.7) (thickness 0.15)) (justify left bottom mirror))
    )
    (fp_text user "Author: Antmicro" (at -0.95 -4.169 180) (layer "B.Fab") hide
        (effects (font (size 0.7 0.7) (thickness 0.15)) (justify left bottom mirror))
    )
    (fp_text user "License: Apache-2.0" (at -0.95 -5.169 180) (layer "B.Fab") hide
        (effects (font (size 0.7 0.7) (thickness 0.15)) (justify left bottom mirror))
    )
    (fp_text user "${REFERENCE}" (at -0.95 -3.168 180) (layer "B.Fab") hide
        (effects (font (size 0.7 0.7) (thickness 0.15)) (justify left bottom mirror))
    )
    (fp_rect (start -0.925 0.47) (end 0.925 -0.47)
      (stroke (width 0.05) (type default)) (fill none) (layer "B.CrtYd"))
    (fp_rect (start -0.5 0.25) (end 0.5 -0.25)
      (stroke (width 0.15) (type solid)) (fill none) (layer "B.Fab"))
    (pad "1" smd roundrect (at -0.48 0) (size 0.59 0.64) (layers "B.Cu" "B.Paste" "B.Mask") (roundrect_rratio 0.25)
      (net 65 "SPI_CS") (pintype "passive"))
    (pad "2" smd roundrect (at 0.48 0) (size 0.59 0.64) (layers "B.Cu" "B.Paste" "B.Mask") (roundrect_rratio 0.25)
      (net 2 "3V3_SYS") (pintype "passive"))
  )
)
